(kicad_pcb
	(version 20240108)
	(generator "pcbnew")
	(generator_version "8.0")
	(general
		(thickness 1.62)
		(legacy_teardrops no)
	)
	(paper "A4")
	(title_block
		(title "Jetson Orin Baseboard")
		(date "2025-03-12")
		(rev "1.3.4")
		(company "Antmicro Ltd")
		(comment 1 "www.antmicro.com")
		(comment 9 "footprints 622-626 of 677")
	)
	(layers
		(0 "F.Cu" signal)
		(1 "In1.Cu" signal)
		(2 "In2.Cu" signal)
		(3 "In3.Cu" signal)
		(4 "In4.Cu" jumper)
		(5 "In5.Cu" signal)
		(6 "In6.Cu" signal)
		(31 "B.Cu" signal)
		(32 "B.Adhes" user "B.Adhesive")
		(33 "F.Adhes" user "F.Adhesive")
		(34 "B.Paste" user)
		(35 "F.Paste" user)
		(36 "B.SilkS" user "B.Silkscreen")
		(37 "F.SilkS" user "F.Silkscreen")
		(38 "B.Mask" user)
		(39 "F.Mask" user)
		(40 "Dwgs.User" user "User.Drawings")
		(41 "Cmts.User" user "User.Comments")
		(42 "Eco1.User" user "User.Eco1")
		(43 "Eco2.User" user "User.Eco2")
		(44 "Edge.Cuts" user)
		(45 "Margin" user)
		(46 "B.CrtYd" user "B.Courtyard")
		(47 "F.CrtYd" user "F.Courtyard")
		(48 "B.Fab" user)
		(49 "F.Fab" user)
	)
	(footprint "antmicro-footprints:C_0402_1005Metric"
		(layer "B.Cu")
		(at 114.6 80.4)
		(descr "Capacitor SMD 0402")
		(tags "capacitor SMD 0402")
		(property "Reference" "C25"
			(at 1.15 -0.4 180)
			(layer "B.SilkS")
			(effects
				(font
					(size 0.7 0.7)
					(thickness 0.15)
				)
				(justify left bottom mirror)
			)
		)
		(property "Value" "C_100n_0402"
			(at 0 -1.4 180)
			(layer "B.Fab")
			(effects
				(font
					(size 0.7 0.7)
					(thickness 0.15)
				)
				(justify left bottom mirror)
			)
		)
		(property "Footprint" "antmicro-footprints:C_0402_1005Metric"
			(at 0 0 0)
			(layer "F.Fab")
			(hide yes)
			(effects
				(font
					(size 1.27 1.27)
					(thickness 0.15)
				)
			)
		)
		(property "Datasheet" "https://www.murata.com/products/productdetail?partno=GRM155R61H104KE14%23"
			(at 0 0 0)
			(layer "F.Fab")
			(hide yes)
			(effects
				(font
					(size 1.27 1.27)
					(thickness 0.15)
				)
			)
		)
		(property "Author" "Antmicro"
			(at 0 0 0)
			(layer "B.Fab")
			(hide yes)
			(effects
				(font
					(size 1 1)
					(thickness 0.15)
				)
				(justify mirror)
			)
		)
		(property "Dielectric" "X5R"
			(at 0 0 0)
			(layer "B.Fab")
			(hide yes)
			(effects
				(font
					(size 1 1)
					(thickness 0.15)
				)
				(justify mirror)
			)
		)
		(property "License" "Apache-2.0"
			(at 0 0 0)
			(layer "B.Fab")
			(hide yes)
			(effects
				(font
					(size 1 1)
					(thickness 0.15)
				)
				(justify mirror)
			)
		)
		(property "MPN" "GRM155R61H104KE14D"
			(at 0 0 0)
			(layer "B.Fab")
			(hide yes)
			(effects
				(font
					(size 1 1)
					(thickness 0.15)
				)
				(justify mirror)
			)
		)
		(property "Manufacturer" "Murata"
			(at 0 0 0)
			(layer "B.Fab")
			(hide yes)
			(effects
				(font
					(size 1 1)
					(thickness 0.15)
				)
				(justify mirror)
			)
		)
		(property "Val" "100n"
			(at 0 0 0)
			(layer "B.Fab")
			(hide yes)
			(effects
				(font
					(size 1 1)
					(thickness 0.15)
				)
				(justify mirror)
			)
		)
		(property "Voltage" "50V"
			(at 0 0 0)
			(layer "B.Fab")
			(hide yes)
			(effects
				(font
					(size 1 1)
					(thickness 0.15)
				)
				(justify mirror)
			)
		)
		(sheetname "M.2")
		(sheetfile "m-2.kicad_sch")
		(attr smd)
		(fp_rect
			(start -0.925 0.47)
			(end 0.925 -0.47)
			(stroke
				(width 0.05)
				(type default)
			)
			(fill none)
			(layer "B.CrtYd")
		)
		(fp_line
			(start -0.494 -0.248)
			(end 0.504 -0.248)
			(stroke
				(width 0.15)
				(type solid)
			)
			(layer "B.Fab")
		)
		(fp_line
			(start -0.494 0.25)
			(end -0.494 -0.248)
			(stroke
				(width 0.15)
				(type solid)
			)
			(layer "B.Fab")
		)
		(fp_line
			(start 0.504 -0.248)
			(end 0.504 0.25)
			(stroke
				(width 0.15)
				(type solid)
			)
			(layer "B.Fab")
		)
		(fp_line
			(start 0.504 0.25)
			(end -0.494 0.25)
			(stroke
				(width 0.15)
				(type solid)
			)
			(layer "B.Fab")
		)
		(fp_text user "License: Apache-2.0"
			(at -0.932 -5.17 180)
			(layer "B.Fab")
			(hide yes)
			(effects
				(font
					(size 0.7 0.7)
					(thickness 0.15)
				)
				(justify left bottom mirror)
			)
		)
		(fp_text user "Author: Antmicro"
			(at -0.932 -4.17 180)
			(layer "B.Fab")
			(hide yes)
			(effects
				(font
					(size 0.7 0.7)
					(thickness 0.15)
				)
				(justify left bottom mirror)
			)
		)
		(fp_text user "${REFERENCE}"
			(at -0.932 -3.168 180)
			(layer "B.Fab")
			(hide yes)
			(effects
				(font
					(size 0.7 0.7)
					(thickness 0.15)
				)
				(justify left bottom mirror)
			)
		)
		(pad "1" smd roundrect
			(at -0.48 0)
			(size 0.59 0.64)
			(layers "B.Cu" "B.Paste" "B.Mask")
			(roundrect_rratio 0.25)
			(net 87 "+3V3")
			(pintype "passive")
		)
		(pad "2" smd roundrect
			(at 0.48 0)
			(size 0.59 0.64)
			(layers "B.Cu" "B.Paste" "B.Mask")
			(roundrect_rratio 0.25)
			(net 1 "GND")
			(pintype "passive")
		)
	)
	(footprint "antmicro-footprints:R_0603_1608Metric"
		(layer "B.Cu")
		(at 63.65 109.9 -90)
		(descr "Resistor SMD 0603")
		(tags "resistor SMD 0603")
		(property "Reference" "R252"
			(at 1.22 -0.22 90)
			(layer "B.SilkS")
			(effects
				(font
					(size 0.7 0.7)
					(thickness 0.15)
				)
				(justify left bottom mirror)
			)
		)
		(property "Value" "R_0R_22.4A_0603"
			(at 0 -1.6 90)
			(layer "B.Fab")
			(effects
				(font
					(size 0.7 0.7)
					(thickness 0.15)
				)
				(justify left bottom mirror)
			)
		)
		(property "Footprint" "antmicro-footprints:R_0603_1608Metric"
			(at 0 0 -90)
			(layer "F.Fab")
			(hide yes)
			(effects
				(font
					(size 1.27 1.27)
					(thickness 0.15)
				)
			)
		)
		(property "Datasheet" "https://fscdn.rohm.com/en/products/databook/datasheet/passive/resistor/chip_resistor/pmr-jpw-e.pdf"
			(at 0 0 -90)
			(layer "F.Fab")
			(hide yes)
			(effects
				(font
					(size 1.27 1.27)
					(thickness 0.15)
				)
			)
		)
		(property "Author" "Antmicro"
			(at -46.25 173.55 0)
			(layer "B.Fab")
			(hide yes)
			(effects
				(font
					(size 1 1)
					(thickness 0.15)
				)
				(justify mirror)
			)
		)
		(property "License" "Apache-2.0"
			(at -46.25 173.55 0)
			(layer "B.Fab")
			(hide yes)
			(effects
				(font
					(size 1 1)
					(thickness 0.15)
				)
				(justify mirror)
			)
		)
		(property "MPN" "PMR03EZPJ000"
			(at -46.25 173.55 0)
			(layer "B.Fab")
			(hide yes)
			(effects
				(font
					(size 1 1)
					(thickness 0.15)
				)
				(justify mirror)
			)
		)
		(property "Manufacturer" "ROHM Semiconductor"
			(at -46.25 173.55 0)
			(layer "B.Fab")
			(hide yes)
			(effects
				(font
					(size 1 1)
					(thickness 0.15)
				)
				(justify mirror)
			)
		)
		(property "Max. Curr." "22.4A"
			(at -46.25 173.55 0)
			(layer "B.Fab")
			(hide yes)
			(effects
				(font
					(size 1 1)
					(thickness 0.15)
				)
				(justify mirror)
			)
		)
		(property "Tolerance" "template_tolerance"
			(at -46.25 173.55 0)
			(layer "B.Fab")
			(hide yes)
			(effects
				(font
					(size 1 1)
					(thickness 0.15)
				)
				(justify mirror)
			)
		)
		(property "Val" "0R"
			(at -46.25 173.55 0)
			(layer "B.Fab")
			(hide yes)
			(effects
				(font
					(size 1 1)
					(thickness 0.15)
				)
				(justify mirror)
			)
		)
		(sheetname "Supply")
		(sheetfile "supply.kicad_sch")
		(attr smd)
		(fp_line
			(start 0.15 0.4)
			(end -0.15 0.4)
			(stroke
				(width 0.15)
				(type solid)
			)
			(layer "B.SilkS")
		)
		(fp_line
			(start 0.15 -0.4)
			(end -0.15 -0.4)
			(stroke
				(width 0.15)
				(type solid)
			)
			(layer "B.SilkS")
		)
		(fp_rect
			(start -1.25 0.65)
			(end 1.25 -0.65)
			(stroke
				(width 0.05)
				(type solid)
			)
			(fill none)
			(layer "B.CrtYd")
		)
		(fp_rect
			(start -0.8 0.4)
			(end 0.8 -0.4)
			(stroke
				(width 0.15)
				(type solid)
			)
			(fill none)
			(layer "B.Fab")
		)
		(fp_text user "${REFERENCE}"
			(at -1.25 -3.898 90)
			(layer "B.Fab")
			(hide yes)
			(effects
				(font
					(size 0.7 0.7)
					(thickness 0.15)
				)
				(justify left bottom mirror)
			)
		)
		(fp_text user "Author: Antmicro"
			(at -1.25 -4.9 90)
			(layer "B.Fab")
			(hide yes)
			(effects
				(font
					(size 0.7 0.7)
					(thickness 0.15)
				)
				(justify left bottom mirror)
			)
		)
		(fp_text user "License: Apache-2.0"
			(at -1.25 -5.9 90)
			(layer "B.Fab")
			(hide yes)
			(effects
				(font
					(size 0.7 0.7)
					(thickness 0.15)
				)
				(justify left bottom mirror)
			)
		)
		(pad "1" smd roundrect
			(at -0.7 0 270)
			(size 0.8 1)
			(layers "B.Cu" "B.Paste" "B.Mask")
			(roundrect_rratio 0.2)
			(net 480 "USBPD1_HV")
			(pintype "passive")
		)
		(pad "2" smd roundrect
			(at 0.7 0 270)
			(size 0.8 1)
			(layers "B.Cu" "B.Paste" "B.Mask")
			(roundrect_rratio 0.2)
			(net 328 "/Supply/VCC_IN")
			(pintype "passive")
		)
	)
	(footprint "antmicro-footprints:C_0402_1005Metric"
		(layer "B.Cu")
		(at 56.3 77.2)
		(descr "Capacitor SMD 0402")
		(tags "capacitor SMD 0402")
		(property "Reference" "C117"
			(at 20.11 9.22 0)
			(layer "B.SilkS")
			(effects
				(font
					(size 0.7 0.7)
					(thickness 0.15)
				)
				(justify right bottom mirror)
			)
		)
		(property "Value" "C_10u_0402"
			(at 0 -1.4 0)
			(layer "B.Fab")
			(effects
				(font
					(size 0.7 0.7)
					(thickness 0.15)
				)
				(justify right bottom mirror)
			)
		)
		(property "Footprint" "antmicro-footprints:C_0402_1005Metric"
			(at 0 0 0)
			(layer "F.Fab")
			(hide yes)
			(effects
				(font
					(size 1.27 1.27)
					(thickness 0.15)
				)
			)
		)
		(property "Datasheet" "https://www.yageo.com/en/Chart/Download/pdf/CC0402MRX5R5BB106"
			(at 0 0 0)
			(layer "F.Fab")
			(hide yes)
			(effects
				(font
					(size 1.27 1.27)
					(thickness 0.15)
				)
			)
		)
		(property "Author" "Antmicro"
			(at 0 0 0)
			(layer "B.Fab")
			(hide yes)
			(effects
				(font
					(size 1 1)
					(thickness 0.15)
				)
				(justify mirror)
			)
		)
		(property "Dielectric" ""
			(at 0 0 0)
			(layer "B.Fab")
			(hide yes)
			(effects
				(font
					(size 1 1)
					(thickness 0.15)
				)
				(justify mirror)
			)
		)
		(property "License" "Apache-2.0"
			(at 0 0 0)
			(layer "B.Fab")
			(hide yes)
			(effects
				(font
					(size 1 1)
					(thickness 0.15)
				)
				(justify mirror)
			)
		)
		(property "MPN" "CC0402MRX5R5BB106"
			(at 0 0 0)
			(layer "B.Fab")
			(hide yes)
			(effects
				(font
					(size 1 1)
					(thickness 0.15)
				)
				(justify mirror)
			)
		)
		(property "Manufacturer" "YAGEO"
			(at 0 0 0)
			(layer "B.Fab")
			(hide yes)
			(effects
				(font
					(size 1 1)
					(thickness 0.15)
				)
				(justify mirror)
			)
		)
		(property "Val" "10u"
			(at 0 0 0)
			(layer "B.Fab")
			(hide yes)
			(effects
				(font
					(size 1 1)
					(thickness 0.15)
				)
				(justify mirror)
			)
		)
		(property "Voltage" ""
			(at 0 0 0)
			(layer "B.Fab")
			(hide yes)
			(effects
				(font
					(size 1 1)
					(thickness 0.15)
				)
				(justify mirror)
			)
		)
		(sheetname "Supply")
		(sheetfile "supply.kicad_sch")
		(attr smd)
		(fp_rect
			(start -0.925 0.47)
			(end 0.925 -0.47)
			(stroke
				(width 0.05)
				(type default)
			)
			(fill none)
			(layer "B.CrtYd")
		)
		(fp_line
			(start -0.494 -0.248)
			(end 0.504 -0.248)
			(stroke
				(width 0.15)
				(type solid)
			)
			(layer "B.Fab")
		)
		(fp_line
			(start -0.494 0.25)
			(end -0.494 -0.248)
			(stroke
				(width 0.15)
				(type solid)
			)
			(layer "B.Fab")
		)
		(fp_line
			(start 0.504 -0.248)
			(end 0.504 0.25)
			(stroke
				(width 0.15)
				(type solid)
			)
			(layer "B.Fab")
		)
		(fp_line
			(start 0.504 0.25)
			(end -0.494 0.25)
			(stroke
				(width 0.15)
				(type solid)
			)
			(layer "B.Fab")
		)
		(fp_text user "License: Apache-2.0"
			(at -0.932 -5.17 0)
			(layer "B.Fab")
			(hide yes)
			(effects
				(font
					(size 0.7 0.7)
					(thickness 0.15)
				)
				(justify right bottom mirror)
			)
		)
		(fp_text user "${REFERENCE}"
			(at -0.932 -3.168 0)
			(layer "B.Fab")
			(hide yes)
			(effects
				(font
					(size 0.7 0.7)
					(thickness 0.15)
				)
				(justify right bottom mirror)
			)
		)
		(fp_text user "Author: Antmicro"
			(at -0.932 -4.17 0)
			(layer "B.Fab")
			(hide yes)
			(effects
				(font
					(size 0.7 0.7)
					(thickness 0.15)
				)
				(justify right bottom mirror)
			)
		)
		(pad "1" smd roundrect
			(at -0.48 0)
			(size 0.59 0.64)
			(layers "B.Cu" "B.Paste" "B.Mask")
			(roundrect_rratio 0.25)
			(net 1 "GND")
			(pintype "passive")
		)
		(pad "2" smd roundrect
			(at 0.48 0)
			(size 0.59 0.64)
			(layers "B.Cu" "B.Paste" "B.Mask")
			(roundrect_rratio 0.25)
			(net 174 "Net-(D36-C)")
			(pintype "passive")
		)
	)
	(footprint "antmicro-footprints:R_0402_1005Metric"
		(layer "B.Cu")
		(at 68.2 110.25 90)
		(descr "Resistor SMD 0402")
		(tags "resistor SMD 0402")
		(property "Reference" "R43"
			(at -0.98 0.35 -90)
			(layer "B.SilkS")
			(effects
				(font
					(size 0.7 0.7)
					(thickness 0.15)
				)
				(justify left bottom mirror)
			)
		)
		(property "Value" "R_100k_0402"
			(at 0 -1.4 -90)
			(layer "B.Fab")
			(effects
				(font
					(size 0.7 0.7)
					(thickness 0.15)
				)
				(justify left bottom mirror)
			)
		)
		(property "Footprint" "antmicro-footprints:R_0402_1005Metric"
			(at 0 0 90)
			(layer "F.Fab")
			(hide yes)
			(effects
				(font
					(size 1.27 1.27)
					(thickness 0.15)
				)
			)
		)
		(property "Datasheet" "https://www.bourns.com/docs/product-datasheets/cr.pdf"
			(at 0 0 90)
			(layer "F.Fab")
			(hide yes)
			(effects
				(font
					(size 1.27 1.27)
					(thickness 0.15)
				)
			)
		)
		(property "Author" "Antmicro"
			(at 178.45 42.05 0)
			(layer "B.Fab")
			(hide yes)
			(effects
				(font
					(size 1 1)
					(thickness 0.15)
				)
				(justify mirror)
			)
		)
		(property "License" "Apache-2.0"
			(at 178.45 42.05 0)
			(layer "B.Fab")
			(hide yes)
			(effects
				(font
					(size 1 1)
					(thickness 0.15)
				)
				(justify mirror)
			)
		)
		(property "MPN" "CR0402-FX-1003GLF"
			(at 178.45 42.05 0)
			(layer "B.Fab")
			(hide yes)
			(effects
				(font
					(size 1 1)
					(thickness 0.15)
				)
				(justify mirror)
			)
		)
		(property "Manufacturer" "Bourns"
			(at 178.45 42.05 0)
			(layer "B.Fab")
			(hide yes)
			(effects
				(font
					(size 1 1)
					(thickness 0.15)
				)
				(justify mirror)
			)
		)
		(property "Tolerance" "1%"
			(at 178.45 42.05 0)
			(layer "B.Fab")
			(hide yes)
			(effects
				(font
					(size 1 1)
					(thickness 0.15)
				)
				(justify mirror)
			)
		)
		(property "Val" "100k"
			(at 178.45 42.05 0)
			(layer "B.Fab")
			(hide yes)
			(effects
				(font
					(size 1 1)
					(thickness 0.15)
				)
				(justify mirror)
			)
		)
		(sheetname "USB Debug, DP")
		(sheetfile "usb.kicad_sch")
		(attr smd)
		(fp_rect
			(start -0.925 0.47)
			(end 0.925 -0.47)
			(stroke
				(width 0.05)
				(type default)
			)
			(fill none)
			(layer "B.CrtYd")
		)
		(fp_rect
			(start -0.5 0.25)
			(end 0.5 -0.25)
			(stroke
				(width 0.15)
				(type solid)
			)
			(fill none)
			(layer "B.Fab")
		)
		(fp_text user "Author: Antmicro"
			(at -0.95 -4.169 -90)
			(layer "B.Fab")
			(hide yes)
			(effects
				(font
					(size 0.7 0.7)
					(thickness 0.15)
				)
				(justify left bottom mirror)
			)
		)
		(fp_text user "License: Apache-2.0"
			(at -0.95 -5.169 -90)
			(layer "B.Fab")
			(hide yes)
			(effects
				(font
					(size 0.7 0.7)
					(thickness 0.15)
				)
				(justify left bottom mirror)
			)
		)
		(fp_text user "${REFERENCE}"
			(at -0.95 -3.168 -90)
			(layer "B.Fab")
			(hide yes)
			(effects
				(font
					(size 0.7 0.7)
					(thickness 0.15)
				)
				(justify left bottom mirror)
			)
		)
		(pad "1" smd roundrect
			(at -0.48 0 90)
			(size 0.59 0.64)
			(layers "B.Cu" "B.Paste" "B.Mask")
			(roundrect_rratio 0.25)
			(net 1 "GND")
			(pintype "passive")
		)
		(pad "2" smd roundrect
			(at 0.48 0 90)
			(size 0.59 0.64)
			(layers "B.Cu" "B.Paste" "B.Mask")
			(roundrect_rratio 0.25)
			(net 286 "/USB Debug, DP/PDC_ADCIN1")
			(pintype "passive")
		)
	)
	(footprint "antmicro-footprints:TP_SMD_0.75mm"
		(layer "B.Cu")
		(at 130.085 86.7192)
		(property "Reference" "TP10"
			(at 0.395 0.365001 0)
			(layer "B.SilkS")
			(effects
				(font
					(size 0.7 0.7)
					(thickness 0.15)
				)
				(justify right bottom mirror)
			)
		)
		(property "Value" "TP_0.75mm_SMD"
			(at 0 -1.2 0)
			(layer "B.Fab")
			(effects
				(font
					(size 0.7 0.7)
					(thickness 0.15)
				)
				(justify right bottom mirror)
			)
		)
		(property "Footprint" "antmicro-footprints:TP_SMD_0.75mm"
			(at 0 0 0)
			(layer "F.Fab")
			(hide yes)
			(effects
				(font
					(size 1.27 1.27)
					(thickness 0.15)
				)
			)
		)
		(property "Author" "Antmicro"
			(at 0 0 0)
			(layer "B.Fab")
			(hide yes)
			(effects
				(font
					(size 1 1)
					(thickness 0.15)
				)
				(justify mirror)
			)
		)
		(property "License" "Apache-2.0"
			(at 0 0 0)
			(layer "B.Fab")
			(hide yes)
			(effects
				(font
					(size 1 1)
					(thickness 0.15)
				)
				(justify mirror)
			)
		)
		(property "MPN" ""
			(at 0 0 0)
			(layer "B.Fab")
			(hide yes)
			(effects
				(font
					(size 1 1)
					(thickness 0.15)
				)
				(justify mirror)
			)
		)
		(property "Manufacturer" ""
			(at 0 0 0)
			(layer "B.Fab")
			(hide yes)
			(effects
				(font
					(size 1 1)
					(thickness 0.15)
				)
				(justify mirror)
			)
		)
		(sheetname "M.2")
		(sheetfile "m-2.kicad_sch")
		(attr exclude_from_pos_files exclude_from_bom)
		(fp_circle
			(center 0 0)
			(end 0.475 0)
			(stroke
				(width 0.05)
				(type default)
			)
			(fill none)
			(layer "B.CrtYd")
		)
		(fp_text user "${REFERENCE}"
			(at -0.4 -2.7 0)
			(layer "B.Fab")
			(hide yes)
			(effects
				(font
					(size 0.7 0.7)
					(thickness 0.15)
				)
				(justify right bottom mirror)
			)
		)
		(fp_text user "License: Apache-2.0"
			(at -0.4 -5.101 0)
			(layer "B.Fab")
			(hide yes)
			(effects
				(font
					(size 0.7 0.7)
					(thickness 0.15)
				)
				(justify right bottom mirror)
			)
		)
		(fp_text user "Author: Antmicro"
			(at -0.4 -3.901 0)
			(layer "B.Fab")
			(hide yes)
			(effects
				(font
					(size 0.7 0.7)
					(thickness 0.15)
				)
				(justify right bottom mirror)
			)
		)
		(pad "1" smd circle
			(at 0 0)
			(size 0.75 0.75)
			(layers "B.Cu" "B.Mask")
			(net 246 "/M.2/~{M2_M_ALERT}")
			(pinfunction "1")
			(pintype "passive")
		)
	)
)
